(kicad_pcb
	(version 20221018)
	(generator pcbnew)
	(general
    (thickness 1.518)
  )
	(paper "A4")
	(title_block
    (title "Kria K26 Devboard")
    (date "2024-03-26")
    (rev "1.2.5")
    (comment 1 "www.antmicro.com")
    (comment 2 "Antmicro Ltd.")
		(comment 9 "footprints 275-281 of 660")
	)
	(layers
    (0 "F.Cu" mixed)
    (1 "In1.Cu" power)
    (2 "In2.Cu" mixed)
    (3 "In3.Cu" power)
    (4 "In4.Cu" mixed)
    (5 "In5.Cu" power)
    (6 "In6.Cu" mixed)
    (31 "B.Cu" power)
    (32 "B.Adhes" user "B.Adhesive")
    (33 "F.Adhes" user "F.Adhesive")
    (34 "B.Paste" user)
    (35 "F.Paste" user)
    (36 "B.SilkS" user "B.Silkscreen")
    (37 "F.SilkS" user "F.Silkscreen")
    (38 "B.Mask" user)
    (39 "F.Mask" user)
    (40 "Dwgs.User" user "User.Drawings")
    (41 "Cmts.User" user "User.Comments")
    (42 "Eco1.User" user "User.Eco1")
    (43 "Eco2.User" user "User.Eco2")
    (44 "Edge.Cuts" user)
    (45 "Margin" user)
    (46 "B.CrtYd" user "B.Courtyard")
    (47 "F.CrtYd" user "F.Courtyard")
    (48 "B.Fab" user)
    (49 "F.Fab" user)
  )
	(footprint "kria-k26-devboard-footprints:R_0402_1005Metric" (layer "F.Cu")
    (at 91.29 74.23 180)
    (descr "Resistor SMD 0402")
    (tags "resistor SMD 0402")
    (property "Author" "Antmicro")
    (property "License" "Apache-2.0")
    (property "MPN" "CR0402-FX-49R9GLF")
    (property "Manufacturer" "Bourns")
    (property "Sheetfile" "dp.kicad_sch")
    (property "Sheetname" "Display Port")
    (property "Tolerance" "1%")
    (property "Val" "49R9")
    (property "ki_description" "49R9 resistor in 0402 package with 1% tolerance")
    (attr smd)
    (fp_text reference "R3" (at -6.255 -0.523 180) (layer "F.SilkS")
        (effects (font (size 0.7 0.7) (thickness 0.15)) (justify left bottom))
    )
    (fp_text value "R_49R9_0402" (at 0 1.4 180) (layer "F.Fab") hide
        (effects (font (size 0.7 0.7) (thickness 0.15)) (justify left bottom))
    )
    (fp_text user "Author: Antmicro" (at -0.95 4.169 180) (layer "F.Fab") hide
        (effects (font (size 0.7 0.7) (thickness 0.15)) (justify left bottom))
    )
    (fp_text user "License: Apache-2.0" (at -0.95 5.169 180) (layer "F.Fab") hide
        (effects (font (size 0.7 0.7) (thickness 0.15)) (justify left bottom))
    )
    (fp_text user "${REFERENCE}" (at -0.95 3.168 180) (layer "F.Fab") hide
        (effects (font (size 0.7 0.7) (thickness 0.15)) (justify left bottom))
    )
    (fp_rect (start -0.93 -0.47) (end 0.93 0.47)
      (stroke (width 0.05) (type solid)) (fill none) (layer "F.CrtYd"))
    (fp_rect (start -0.5 -0.25) (end 0.5 0.25)
      (stroke (width 0.15) (type solid)) (fill none) (layer "F.Fab"))
    (pad "1" smd roundrect (at -0.485 0 180) (size 0.59 0.64) (layers "F.Cu" "F.Paste" "F.Mask") (roundrect_rratio 0.25)
      (net 96 "/Display Port/DP_AUX_P") (pintype "passive"))
    (pad "2" smd roundrect (at 0.485 0 180) (size 0.59 0.64) (layers "F.Cu" "F.Paste" "F.Mask") (roundrect_rratio 0.25)
      (net 380 "Net-(R3-Pad2)") (pintype "passive"))
  )
	(footprint "kria-k26-devboard-footprints:C_0402_1005Metric" (layer "F.Cu")
    (at 92.73 72.817 90)
    (descr "Capacitor SMD 0402")
    (tags "capacitor SMD 0402")
    (property "Author" "Antmicro")
    (property "Dielectric" "X5R")
    (property "License" "Apache-2.0")
    (property "MPN" "GRM155R61H104KE14D")
    (property "Manufacturer" "Murata")
    (property "Sheetfile" "dp.kicad_sch")
    (property "Sheetname" "Display Port")
    (property "Val" "100n")
    (property "Voltage" "50V")
    (property "ki_description" " ")
    (attr smd)
    (fp_text reference "C11" (at -1.153 7.345 90) (layer "F.SilkS")
        (effects (font (size 0.7 0.7) (thickness 0.15)) (justify left bottom))
    )
    (fp_text value "C_100n_0402" (at 0 1.4 90) (layer "F.Fab") hide
        (effects (font (size 0.7 0.7) (thickness 0.15)) (justify left bottom))
    )
    (fp_text user "License: Apache-2.0" (at -0.932 5.17 90) (layer "F.Fab") hide
        (effects (font (size 0.7 0.7) (thickness 0.15)) (justify left bottom))
    )
    (fp_text user "${REFERENCE}" (at -0.932 3.168 90) (layer "F.Fab") hide
        (effects (font (size 0.7 0.7) (thickness 0.15)) (justify left bottom))
    )
    (fp_text user "Author: Antmicro" (at -0.932 4.17 90) (layer "F.Fab") hide
        (effects (font (size 0.7 0.7) (thickness 0.15)) (justify left bottom))
    )
    (fp_rect (start -0.94 -0.47) (end 0.94 0.47)
      (stroke (width 0.05) (type solid)) (fill none) (layer "F.CrtYd"))
    (fp_rect (start -0.499 -0.249) (end 0.499 0.249)
      (stroke (width 0.15) (type solid)) (fill none) (layer "F.Fab"))
    (pad "1" smd roundrect (at -0.484 0 90) (size 0.59 0.64) (layers "F.Cu" "F.Paste" "F.Mask") (roundrect_rratio 0.25)
      (net 98 "/Display Port/DP_AUX_N") (pintype "passive"))
    (pad "2" smd roundrect (at 0.484 0 90) (size 0.59 0.64) (layers "F.Cu" "F.Paste" "F.Mask") (roundrect_rratio 0.25)
      (net 99 "/Display Port/DP_AUX_C_N") (pintype "passive"))
  )
	(footprint "kria-k26-devboard-footprints:C_0402_1005Metric" (layer "F.Cu")
    (at 91.78 72.817 90)
    (descr "Capacitor SMD 0402")
    (tags "capacitor SMD 0402")
    (property "Author" "Antmicro")
    (property "Dielectric" "X5R")
    (property "License" "Apache-2.0")
    (property "MPN" "GRM155R61H104KE14D")
    (property "Manufacturer" "Murata")
    (property "Sheetfile" "dp.kicad_sch")
    (property "Sheetname" "Display Port")
    (property "Val" "100n")
    (property "Voltage" "50V")
    (property "ki_description" " ")
    (attr smd)
    (fp_text reference "C10" (at -1.153 7.345 90) (layer "F.SilkS")
        (effects (font (size 0.7 0.7) (thickness 0.15)) (justify left bottom))
    )
    (fp_text value "C_100n_0402" (at 0 1.4 90) (layer "F.Fab") hide
        (effects (font (size 0.7 0.7) (thickness 0.15)) (justify left bottom))
    )
    (fp_text user "Author: Antmicro" (at -0.932 4.17 90) (layer "F.Fab") hide
        (effects (font (size 0.7 0.7) (thickness 0.15)) (justify left bottom))
    )
    (fp_text user "License: Apache-2.0" (at -0.932 5.17 90) (layer "F.Fab") hide
        (effects (font (size 0.7 0.7) (thickness 0.15)) (justify left bottom))
    )
    (fp_text user "${REFERENCE}" (at -0.932 3.168 90) (layer "F.Fab") hide
        (effects (font (size 0.7 0.7) (thickness 0.15)) (justify left bottom))
    )
    (fp_rect (start -0.94 -0.47) (end 0.94 0.47)
      (stroke (width 0.05) (type solid)) (fill none) (layer "F.CrtYd"))
    (fp_rect (start -0.499 -0.249) (end 0.499 0.249)
      (stroke (width 0.15) (type solid)) (fill none) (layer "F.Fab"))
    (pad "1" smd roundrect (at -0.484 0 90) (size 0.59 0.64) (layers "F.Cu" "F.Paste" "F.Mask") (roundrect_rratio 0.25)
      (net 96 "/Display Port/DP_AUX_P") (pintype "passive"))
    (pad "2" smd roundrect (at 0.484 0 90) (size 0.59 0.64) (layers "F.Cu" "F.Paste" "F.Mask") (roundrect_rratio 0.25)
      (net 97 "/Display Port/DP_AUX_C_P") (pintype "passive"))
  )
	(footprint "kria-k26-devboard-footprints:C_0402_1005Metric" (layer "F.Cu")
    (at 147.5 142.95)
    (descr "Capacitor SMD 0402")
    (tags "capacitor SMD 0402")
    (property "Author" "Antmicro")
    (property "Dielectric" "")
    (property "License" "Apache-2.0")
    (property "MPN" "GRM155R71H104KE14D")
    (property "Manufacturer" "Murata")
    (property "Sheetfile" "debug.kicad_sch")
    (property "Sheetname" "Debug and JTAG")
    (property "Val" "100n/50V")
    (property "Voltage" "")
    (property "ki_description" " ")
    (attr smd)
    (fp_text reference "C153" (at -0.97 -0.65) (layer "F.SilkS")
        (effects (font (size 0.7 0.7) (thickness 0.15)) (justify left bottom))
    )
    (fp_text value "C_100n_50V_0402" (at 0 1.4) (layer "F.Fab") hide
        (effects (font (size 0.7 0.7) (thickness 0.15)) (justify left bottom))
    )
    (fp_text user "${REFERENCE}" (at -0.932 3.168) (layer "F.Fab") hide
        (effects (font (size 0.7 0.7) (thickness 0.15)) (justify left bottom))
    )
    (fp_text user "License: Apache-2.0" (at -0.932 5.17) (layer "F.Fab") hide
        (effects (font (size 0.7 0.7) (thickness 0.15)) (justify left bottom))
    )
    (fp_text user "Author: Antmicro" (at -0.932 4.17) (layer "F.Fab") hide
        (effects (font (size 0.7 0.7) (thickness 0.15)) (justify left bottom))
    )
    (fp_rect (start -0.94 -0.47) (end 0.94 0.47)
      (stroke (width 0.05) (type solid)) (fill none) (layer "F.CrtYd"))
    (fp_rect (start -0.499 -0.249) (end 0.499 0.249)
      (stroke (width 0.15) (type solid)) (fill none) (layer "F.Fab"))
    (pad "1" smd roundrect (at -0.484 0) (size 0.59 0.64) (layers "F.Cu" "F.Paste" "F.Mask") (roundrect_rratio 0.25)
      (net 266 "/Debug and JTAG/USBB_VBUS") (pintype "passive"))
    (pad "2" smd roundrect (at 0.484 0) (size 0.59 0.64) (layers "F.Cu" "F.Paste" "F.Mask") (roundrect_rratio 0.25)
      (net 1 "GND") (pintype "passive"))
  )
	(footprint "kria-k26-devboard-footprints:USB-C_Receptacle_GCT_USB4105-GF-A" (layer "F.Cu")
    (at 144.35 147.825)
    (property "Author" "Antmicro")
    (property "DNP" "DNP")
    (property "License" "Apache-2.0")
    (property "MPN" "USB4105-GF-A")
    (property "Manufacturer" "GCT")
    (property "Sheetfile" "debug.kicad_sch")
    (property "Sheetname" "Debug and JTAG")
    (property "VSD_Class" "USB-C")
    (property "dnp" "")
    (property "ki_description" "USB-C (USB TYPE-C) USB 2.0 Receptacle Connector 24 (16+8 Dummy) Position Surface Mount, Right Angle")
    (property "ki_keywords" "USB, CONNECTOR, SMT, HORIZONTAL")
    (attr exclude_from_pos_files)
    (fp_text reference "J8" (at 5.23 3.715) (layer "F.SilkS")
        (effects (font (size 0.7 0.7) (thickness 0.15)) (justify left bottom))
    )
    (fp_text value "USB-C_GCT_USB4105-GF-A" (at 0 5) (layer "F.Fab") hide
        (effects (font (size 0.7 0.7) (thickness 0.15)) (justify left bottom))
    )
    (fp_text user "License: Apache-2.0" (at -4.79 8.855) (layer "F.Fab") hide
        (effects (font (size 0.7 0.7) (thickness 0.15)) (justify left bottom))
    )
    (fp_text user "Author: Antmicro" (at -4.79 7.853) (layer "F.Fab") hide
        (effects (font (size 0.7 0.7) (thickness 0.15)) (justify left bottom))
    )
    (fp_text user "PCB-EDGE" (at -4.79 5.853) (layer "F.Fab") hide
        (effects (font (size 0.7 0.7) (thickness 0.15)) (justify left bottom))
    )
    (fp_text user "${REFERENCE}" (at -4.79 6.853) (layer "F.Fab") hide
        (effects (font (size 0.7 0.7) (thickness 0.15)) (justify left bottom))
    )
    (fp_line (start -4.79 -1.395) (end -4.79 -0.145)
      (stroke (width 0.15) (type solid)) (layer "F.SilkS"))
    (fp_line (start -4.79 2.575) (end -4.79 3.854)
      (stroke (width 0.15) (type solid)) (layer "F.SilkS"))
    (fp_line (start -4.79 3.854) (end 4.788 3.854)
      (stroke (width 0.15) (type solid)) (layer "F.SilkS"))
    (fp_line (start 4.788 -1.395) (end 4.788 -0.145)
      (stroke (width 0.15) (type solid)) (layer "F.SilkS"))
    (fp_line (start 4.788 3.854) (end 4.788 2.575)
      (stroke (width 0.15) (type solid)) (layer "F.SilkS"))
    (fp_circle (center -3.8 -4.27071) (end -3.75 -4.22071)
      (stroke (width 0.15) (type solid)) (fill solid) (layer "F.SilkS"))
    (fp_rect (start -5.1 -4.4) (end 5.1 3.9)
      (stroke (width 0.05) (type solid)) (fill none) (layer "F.CrtYd"))
    (fp_line (start -4.79 -3.676) (end 4.788 -3.676)
      (stroke (width 0.15) (type solid)) (layer "F.Fab"))
    (fp_line (start -4.79 3.854) (end -4.79 -3.676)
      (stroke (width 0.15) (type solid)) (layer "F.Fab"))
    (fp_line (start -4.702 3.854) (end 4.788 3.854)
      (stroke (width 0.15) (type solid)) (layer "F.Fab"))
    (fp_line (start 4.788 -3.676) (end 4.788 3.854)
      (stroke (width 0.15) (type solid)) (layer "F.Fab"))
    (fp_line (start 4.788 3.854) (end -4.79 3.854)
      (stroke (width 0.15) (type solid)) (layer "F.Fab"))
    (pad "" np_thru_hole circle (at -2.891 -2.426) (size 0.65 0.65) (drill 0.65) (layers "*.Cu" "*.Mask"))
    (pad "" np_thru_hole circle (at 2.89 -2.426) (size 0.65 0.65) (drill 0.65) (layers "*.Cu" "*.Mask"))
    (pad "A1" smd roundrect (at -3.202 -3.5) (size 0.6 1.15) (layers "F.Cu" "F.Paste" "F.Mask") (roundrect_rratio 0.25)
      (net 1 "GND") (pinfunction "GND") (pintype "power_in"))
    (pad "A4" smd roundrect (at -2.4 -3.5) (size 0.6 1.15) (layers "F.Cu" "F.Paste" "F.Mask") (roundrect_rratio 0.25)
      (net 266 "/Debug and JTAG/USBB_VBUS") (pinfunction "VBUS") (pintype "passive"))
    (pad "A5" smd roundrect (at -1.25 -3.5) (size 0.3 1.15) (layers "F.Cu" "F.Paste" "F.Mask") (roundrect_rratio 0.25)
      (net 354 "Net-(J8-CC_{1})") (pinfunction "CC_{1}") (pintype "bidirectional"))
    (pad "A6" smd roundrect (at -0.25 -3.5) (size 0.3 1.15) (layers "F.Cu" "F.Paste" "F.Mask") (roundrect_rratio 0.25)
      (net 355 "Net-(J8-D_{A}+)") (pinfunction "D_{A}+") (pintype "bidirectional"))
    (pad "A7" smd roundrect (at 0.248 -3.5) (size 0.3 1.15) (layers "F.Cu" "F.Paste" "F.Mask") (roundrect_rratio 0.25)
      (net 356 "Net-(J8-D_{A}-)") (pinfunction "D_{A}-") (pintype "bidirectional"))
    (pad "A8" smd roundrect (at 1.249 -3.5) (size 0.3 1.15) (layers "F.Cu" "F.Paste" "F.Mask") (roundrect_rratio 0.25)
      (net 357 "unconnected-(J8-SBU_{1}-PadA8)") (pinfunction "SBU_{1}") (pintype "bidirectional+no_connect"))
    (pad "A9" smd roundrect (at 2.398 -3.5) (size 0.6 1.15) (layers "F.Cu" "F.Paste" "F.Mask") (roundrect_rratio 0.25)
      (net 266 "/Debug and JTAG/USBB_VBUS") (pinfunction "VBUS") (pintype "passive"))
    (pad "A12" smd roundrect (at 3.2 -3.5) (size 0.6 1.15) (layers "F.Cu" "F.Paste" "F.Mask") (roundrect_rratio 0.25)
      (net 1 "GND") (pinfunction "GND") (pintype "passive"))
    (pad "B1" smd roundrect (at 3.2 -3.5) (size 0.6 1.15) (layers "F.Cu" "F.Paste" "F.Mask") (roundrect_rratio 0.25)
      (net 1 "GND") (pinfunction "GND") (pintype "passive"))
    (pad "B4" smd roundrect (at 2.398 -3.5) (size 0.6 1.15) (layers "F.Cu" "F.Paste" "F.Mask") (roundrect_rratio 0.25)
      (net 266 "/Debug and JTAG/USBB_VBUS") (pinfunction "VBUS") (pintype "passive"))
    (pad "B5" smd roundrect (at 1.749 -3.5) (size 0.3 1.15) (layers "F.Cu" "F.Paste" "F.Mask") (roundrect_rratio 0.25)
      (net 358 "Net-(J8-CC_{2})") (pinfunction "CC_{2}") (pintype "bidirectional"))
    (pad "B6" smd roundrect (at 0.748 -3.5) (size 0.3 1.15) (layers "F.Cu" "F.Paste" "F.Mask") (roundrect_rratio 0.25)
      (net 355 "Net-(J8-D_{A}+)") (pinfunction "D_{B}+") (pintype "bidirectional"))
    (pad "B7" smd roundrect (at -0.75 -3.5) (size 0.3 1.15) (layers "F.Cu" "F.Paste" "F.Mask") (roundrect_rratio 0.25)
      (net 356 "Net-(J8-D_{A}-)") (pinfunction "D_{B}-") (pintype "bidirectional"))
    (pad "B8" smd roundrect (at -1.75 -3.5) (size 0.3 1.15) (layers "F.Cu" "F.Paste" "F.Mask") (roundrect_rratio 0.25)
      (net 359 "unconnected-(J8-SBU_{2}-PadB8)") (pinfunction "SBU_{2}") (pintype "bidirectional+no_connect"))
    (pad "B9" smd roundrect (at -2.4 -3.5) (size 0.6 1.15) (layers "F.Cu" "F.Paste" "F.Mask") (roundrect_rratio 0.25)
      (net 266 "/Debug and JTAG/USBB_VBUS") (pinfunction "VBUS") (pintype "passive"))
    (pad "B12" smd roundrect (at -3.202 -3.5) (size 0.6 1.15) (layers "F.Cu" "F.Paste" "F.Mask") (roundrect_rratio 0.25)
      (net 1 "GND") (pinfunction "GND") (pintype "passive"))
    (pad "SH" thru_hole oval (at -4.321 -2.926) (size 1.05 2.1) (drill oval 0.6 1.7) (layers "*.Cu" "*.Mask")
      (net 318 "SH_DOWN") (pinfunction "SH") (pintype "passive"))
    (pad "SH" thru_hole oval (at -4.321 1.255) (size 1 2) (drill oval 0.6 1.4) (layers "*.Cu" "*.Mask")
      (net 318 "SH_DOWN") (pinfunction "SH") (pintype "passive"))
    (pad "SH" thru_hole oval (at 4.32 -2.926) (size 1.05 2.1) (drill oval 0.6 1.7) (layers "*.Cu" "*.Mask")
      (net 318 "SH_DOWN") (pinfunction "SH") (pintype "passive"))
    (pad "SH" thru_hole oval (at 4.32 1.255) (size 1 2) (drill oval 0.6 1.4) (layers "*.Cu" "*.Mask")
      (net 318 "SH_DOWN") (pinfunction "SH") (pintype "passive"))
  )
	(footprint "kria-k26-devboard-footprints:R_0402_1005Metric" (layer "F.Cu")
    (at 87.285 116.81 180)
    (descr "Resistor SMD 0402")
    (tags "resistor SMD 0402")
    (property "Author" "Antmicro")
    (property "License" "Apache-2.0")
    (property "MPN" "CR0402-FX-4700GLF")
    (property "Manufacturer" "Bourns")
    (property "Sheetfile" "k26_som.kicad_sch")
    (property "Sheetname" "Xilinx K26 SOM")
    (property "Tolerance" "1%")
    (property "Val" "470R")
    (property "ki_description" "470R resistor in 0402 package with 1% tolerance")
    (attr smd)
    (fp_text reference "R79" (at 0.81 5.32 180) (layer "F.SilkS")
        (effects (font (size 0.7 0.7) (thickness 0.15)) (justify left bottom))
    )
    (fp_text value "R_470R_0402" (at 0 1.4 180) (layer "F.Fab") hide
        (effects (font (size 0.7 0.7) (thickness 0.15)) (justify left bottom))
    )
    (fp_text user "Author: Antmicro" (at -0.95 4.169 180) (layer "F.Fab") hide
        (effects (font (size 0.7 0.7) (thickness 0.15)) (justify left bottom))
    )
    (fp_text user "License: Apache-2.0" (at -0.95 5.169 180) (layer "F.Fab") hide
        (effects (font (size 0.7 0.7) (thickness 0.15)) (justify left bottom))
    )
    (fp_text user "${REFERENCE}" (at -0.95 3.168 180) (layer "F.Fab") hide
        (effects (font (size 0.7 0.7) (thickness 0.15)) (justify left bottom))
    )
    (fp_rect (start -0.93 -0.47) (end 0.93 0.47)
      (stroke (width 0.05) (type solid)) (fill none) (layer "F.CrtYd"))
    (fp_rect (start -0.5 -0.25) (end 0.5 0.25)
      (stroke (width 0.15) (type solid)) (fill none) (layer "F.Fab"))
    (pad "1" smd roundrect (at -0.485 0 180) (size 0.59 0.64) (layers "F.Cu" "F.Paste" "F.Mask") (roundrect_rratio 0.25)
      (net 5 "/Xilinx K26 SOM/MODE3_C2M") (pintype "passive"))
    (pad "2" smd roundrect (at 0.485 0 180) (size 0.59 0.64) (layers "F.Cu" "F.Paste" "F.Mask") (roundrect_rratio 0.25)
      (net 1 "GND") (pintype "passive"))
  )
	(footprint "kria-k26-devboard-footprints:C_0402_1005Metric" (layer "F.Cu")
    (at 111.6 143.59 180)
    (descr "Capacitor SMD 0402")
    (tags "capacitor SMD 0402")
    (property "Author" "Antmicro")
    (property "Dielectric" "X5R")
    (property "License" "Apache-2.0")
    (property "MPN" "GRM155R61H104KE14D")
    (property "Manufacturer" "Murata")
    (property "Sheetfile" "reset.kicad_sch")
    (property "Sheetname" "Reset logic")
    (property "Val" "100n")
    (property "Voltage" "50V")
    (property "ki_description" " ")
    (attr smd)
    (fp_text reference "C139" (at -0.86 -0.45 180) (layer "F.SilkS")
        (effects (font (size 0.7 0.7) (thickness 0.15)) (justify left bottom))
    )
    (fp_text value "C_100n_0402" (at 0 1.4 180) (layer "F.Fab") hide
        (effects (font (size 0.7 0.7) (thickness 0.15)) (justify left bottom))
    )
    (fp_text user "Author: Antmicro" (at -0.932 4.17 180) (layer "F.Fab") hide
        (effects (font (size 0.7 0.7) (thickness 0.15)) (justify left bottom))
    )
    (fp_text user "${REFERENCE}" (at -0.932 3.168 180) (layer "F.Fab") hide
        (effects (font (size 0.7 0.7) (thickness 0.15)) (justify left bottom))
    )
    (fp_text user "License: Apache-2.0" (at -0.932 5.17 180) (layer "F.Fab") hide
        (effects (font (size 0.7 0.7) (thickness 0.15)) (justify left bottom))
    )
    (fp_rect (start -0.9659 -0.481258) (end 0.9649 0.458742)
      (stroke (width 0.05) (type solid)) (fill none) (layer "F.CrtYd"))
    (fp_line (start -0.499 -0.25) (end 0.499 -0.25)
      (stroke (width 0.15) (type solid)) (layer "F.Fab"))
    (fp_line (start -0.499 0.248) (end -0.499 -0.25)
      (stroke (width 0.15) (type solid)) (layer "F.Fab"))
    (fp_line (start 0.499 -0.25) (end 0.499 0.248)
      (stroke (width 0.15) (type solid)) (layer "F.Fab"))
    (fp_line (start 0.499 0.248) (end -0.499 0.248)
      (stroke (width 0.15) (type solid)) (layer "F.Fab"))
    (pad "1" smd roundrect (at -0.484 0 180) (size 0.59 0.64) (layers "F.Cu" "F.Paste" "F.Mask") (roundrect_rratio 0.25)
      (net 15 "PS_3V3") (pintype "passive"))
    (pad "2" smd roundrect (at 0.484 0 180) (size 0.59 0.64) (layers "F.Cu" "F.Paste" "F.Mask") (roundrect_rratio 0.25)
      (net 1 "GND") (pintype "passive"))
  )
)
